(kicad_pcb
	(version 20260206)
	(generator "pcbnew")
	(generator_version "10.0")
	(general
		(thickness 1.6)
		(legacy_teardrops no)
	)
	(paper "A4")
	(title_block
		(title "v1-chassis-manager — T6M_CM_d_v01_1031_1645.brd")
		(comment 1 "Open CloudServer (Microsoft) / footprints 1078-1087 of 2512")
	)
	(layers
		(0 "F.Cu" signal "TOP")
		(4 "In1.Cu" signal "GND1")
		(6 "In2.Cu" signal "IN1")
		(8 "In3.Cu" signal "VCC1")
		(10 "In4.Cu" signal "VCC2")
		(12 "In5.Cu" signal "GND2")
		(14 "In6.Cu" signal "IN2")
		(16 "In7.Cu" signal "IN3")
		(18 "In8.Cu" signal "GND3")
		(2 "B.Cu" signal "BOTTOM")
		(9 "F.Adhes" user "F.Adhesive")
		(11 "B.Adhes" user "B.Adhesive")
		(13 "F.Paste" user "Package Geometry/Pastemask Top")
		(15 "B.Paste" user "Package Geometry/Pastemask Bottom")
		(5 "F.SilkS" user "Ref Des/Silkscreen Top")
		(7 "B.SilkS" user "Ref Des/Silkscreen Bottom")
		(1 "F.Mask" user "Board Geometry/Soldermask Top")
		(3 "B.Mask" user "Board Geometry/Soldermask Bottom")
		(17 "Dwgs.User" user "User.Drawings")
		(19 "Cmts.User" user "User.Comments")
		(21 "Eco1.User" user "User.Eco1")
		(23 "Eco2.User" user "User.Eco2")
		(25 "Edge.Cuts" user "Board Geometry/Outline")
		(27 "Margin" user)
		(31 "F.CrtYd" user "Package Geometry/Place Bound Top")
		(29 "B.CrtYd" user "Package Geometry/Place Bound Bottom")
		(35 "F.Fab" user "Ref Des/Assembly Top")
		(33 "B.Fab" user "Ref Des/Assembly Bottom")
	)
	(footprint ""
		(layer "F.Cu")
		(at 76.419456 -150.293578)
		(property "Reference" "PC1"
			(at -1.18999 1.655826 0)
			(unlocked yes)
			(layer "F.SilkS")
			(effects
				(font
					(size 0.7874 0.5842)
					(thickness 0.1524)
				)
				(justify left)
			)
		)
		(property "Value" ""
			(at 0 0 0)
			(layer "F.Fab")
			(effects
				(font
					(size 1.27 1.27)
				)
			)
		)
		(duplicate_pad_numbers_are_jumpers no)
		(fp_line
			(start -2.2098 -0.9398)
			(end 2.2098 -0.9398)
			(stroke
				(width 0.1524)
				(type default)
			)
			(layer "F.SilkS")
		)
		(fp_line
			(start -2.2098 0.9398)
			(end -2.2098 -0.9398)
			(stroke
				(width 0.1524)
				(type default)
			)
			(layer "F.SilkS")
		)
		(fp_line
			(start 0 -0.9398)
			(end 0 0.9398)
			(stroke
				(width 0.1524)
				(type default)
			)
			(layer "F.SilkS")
		)
		(fp_line
			(start 2.2098 -0.9398)
			(end 2.2098 0.9398)
			(stroke
				(width 0.1524)
				(type default)
			)
			(layer "F.SilkS")
		)
		(fp_line
			(start 2.2098 0.9398)
			(end -2.2098 0.9398)
			(stroke
				(width 0.1524)
				(type default)
			)
			(layer "F.SilkS")
		)
		(fp_poly
			(pts
				(xy -1.6764 0.889) (xy -1.6764 0.7874) (xy -2.0574 0.7874) (xy -2.0574 -0.7874) (xy -1.6764 -0.7874)
				(xy -1.6764 -0.9398) (xy 1.6764 -0.9398) (xy 1.6764 -0.7874) (xy 2.0574 -0.7874) (xy 2.0574 0.7874)
				(xy 1.6764 0.7874) (xy 1.6764 0.9398) (xy -1.6764 0.9398)
			)
			(stroke
				(width 0)
				(type default)
			)
			(fill no)
			(layer "F.CrtYd")
		)
		(fp_line
			(start -1.700022 -0.899922)
			(end 1.700022 -0.899922)
			(stroke
				(width 0.1)
				(type default)
			)
			(layer "F.Fab")
		)
		(fp_line
			(start -1.700022 0.899922)
			(end -1.700022 -0.899922)
			(stroke
				(width 0.1)
				(type default)
			)
			(layer "F.Fab")
		)
		(fp_line
			(start 1.700022 -0.899922)
			(end 1.700022 0.899922)
			(stroke
				(width 0.1)
				(type default)
			)
			(layer "F.Fab")
		)
		(fp_line
			(start 1.700022 0.899922)
			(end -1.700022 0.899922)
			(stroke
				(width 0.1)
				(type default)
			)
			(layer "F.Fab")
		)
		(pad "1" smd rect
			(at 1.4732 0)
			(size 1.1684 1.5748)
			(layers "F.Cu" "F.Mask" "F.Paste")
			(net "P12V_AUX")
		)
		(pad "2" smd rect
			(at -1.4732 0)
			(size 1.1684 1.5748)
			(layers "F.Cu" "F.Mask" "F.Paste")
			(net "GND")
		)
	)
	(footprint ""
		(layer "F.Cu")
		(at 133.71576 -110.783624 -90)
		(property "Reference" "R17"
			(at 5.84835 -0.882142 90)
			(unlocked yes)
			(layer "F.SilkS")
			(effects
				(font
					(size 0.7874 0.5842)
					(thickness 0.1524)
				)
				(justify left)
			)
		)
		(property "Value" ""
			(at 0 0 270)
			(layer "F.Fab")
			(effects
				(font
					(size 1.27 1.27)
				)
			)
		)
		(duplicate_pad_numbers_are_jumpers no)
		(fp_line
			(start -0.7874 0.4064)
			(end -0.7874 -0.4064)
			(stroke
				(width 0.1524)
				(type default)
			)
			(layer "F.SilkS")
		)
		(fp_line
			(start 0.7874 0.4064)
			(end -0.7874 0.4064)
			(stroke
				(width 0.1524)
				(type default)
			)
			(layer "F.SilkS")
		)
		(fp_line
			(start -0.7874 -0.4064)
			(end 0.7874 -0.4064)
			(stroke
				(width 0.1524)
				(type default)
			)
			(layer "F.SilkS")
		)
		(fp_line
			(start 0.7874 -0.4064)
			(end 0.7874 0.4064)
			(stroke
				(width 0.1524)
				(type default)
			)
			(layer "F.SilkS")
		)
		(fp_poly
			(pts
				(xy -0.508 0.2794) (xy -0.508 0.2286) (xy -0.635 0.2286) (xy -0.635 -0.254) (xy -0.5334 -0.254)
				(xy -0.5334 -0.2794) (xy 0.5334 -0.2794) (xy 0.5334 -0.254) (xy 0.635 -0.254) (xy 0.635 0.254) (xy 0.5334 0.254)
				(xy 0.5334 0.2794)
			)
			(stroke
				(width 0)
				(type default)
			)
			(fill no)
			(layer "F.CrtYd")
		)
		(pad "1" smd rect
			(at 0.40005 0 270)
			(size 0.4572 0.508)
			(layers "F.Cu" "F.Mask" "F.Paste")
			(net "GND")
		)
		(pad "2" smd rect
			(at -0.40005 0 270)
			(size 0.4572 0.508)
			(layers "F.Cu" "F.Mask" "F.Paste")
			(net "CLP_ITP_EN_NODE1")
		)
	)
	(footprint ""
		(layer "F.Cu")
		(at 67.924934 -2.944114 -90)
		(property "Reference" "PR18"
			(at 2.74828 2.869184 90)
			(unlocked yes)
			(layer "F.SilkS")
			(effects
				(font
					(size 0.7874 0.5842)
					(thickness 0.1524)
				)
				(justify left)
			)
		)
		(property "Value" ""
			(at 0 0 270)
			(layer "F.Fab")
			(effects
				(font
					(size 1.27 1.27)
				)
			)
		)
		(duplicate_pad_numbers_are_jumpers no)
		(fp_line
			(start -0.7874 0.4064)
			(end -0.7874 -0.4064)
			(stroke
				(width 0.1524)
				(type default)
			)
			(layer "F.SilkS")
		)
		(fp_line
			(start 0.7874 0.4064)
			(end -0.7874 0.4064)
			(stroke
				(width 0.1524)
				(type default)
			)
			(layer "F.SilkS")
		)
		(fp_line
			(start -0.7874 -0.4064)
			(end 0.7874 -0.4064)
			(stroke
				(width 0.1524)
				(type default)
			)
			(layer "F.SilkS")
		)
		(fp_line
			(start 0.7874 -0.4064)
			(end 0.7874 0.4064)
			(stroke
				(width 0.1524)
				(type default)
			)
			(layer "F.SilkS")
		)
		(fp_poly
			(pts
				(xy -0.508 0.2794) (xy -0.508 0.2286) (xy -0.635 0.2286) (xy -0.635 -0.254) (xy -0.5334 -0.254)
				(xy -0.5334 -0.2794) (xy 0.5334 -0.2794) (xy 0.5334 -0.254) (xy 0.635 -0.254) (xy 0.635 0.254) (xy 0.5334 0.254)
				(xy 0.5334 0.2794)
			)
			(stroke
				(width 0)
				(type default)
			)
			(fill no)
			(layer "F.CrtYd")
		)
		(pad "1" smd rect
			(at 0.40005 0 270)
			(size 0.4572 0.508)
			(layers "F.Cu" "F.Mask" "F.Paste")
			(net "P3V3_NODE1_VREG5")
		)
		(pad "2" smd rect
			(at -0.40005 0 270)
			(size 0.4572 0.508)
			(layers "F.Cu" "F.Mask" "F.Paste")
			(net "PWRGD_NODE1_P3V3_PG")
		)
	)
	(footprint ""
		(layer "F.Cu")
		(at 77.138022 -17.664176 90)
		(property "Reference" "C176"
			(at -3.058414 5.652262 90)
			(unlocked yes)
			(layer "F.SilkS")
			(effects
				(font
					(size 0.7874 0.5842)
					(thickness 0.1524)
				)
			)
		)
		(property "Value" ""
			(at 0 0 90)
			(layer "F.Fab")
			(effects
				(font
					(size 1.27 1.27)
				)
			)
		)
		(duplicate_pad_numbers_are_jumpers no)
		(fp_line
			(start 1.2954 -0.5842)
			(end 1.2954 0.5842)
			(stroke
				(width 0.1524)
				(type default)
			)
			(layer "F.SilkS")
		)
		(fp_line
			(start 0 -0.5842)
			(end 0 0.5842)
			(stroke
				(width 0.1524)
				(type default)
			)
			(layer "F.SilkS")
		)
		(fp_line
			(start -1.2954 -0.5842)
			(end 1.2954 -0.5842)
			(stroke
				(width 0.1524)
				(type default)
			)
			(layer "F.SilkS")
		)
		(fp_line
			(start 1.2954 0.5842)
			(end -1.2954 0.5842)
			(stroke
				(width 0.1524)
				(type default)
			)
			(layer "F.SilkS")
		)
		(fp_line
			(start -1.2954 0.5842)
			(end -1.2954 -0.5842)
			(stroke
				(width 0.1524)
				(type default)
			)
			(layer "F.SilkS")
		)
		(fp_poly
			(pts
				(xy 0.8636 -0.4572) (xy 0.8636 -0.3556) (xy 1.143 -0.3556) (xy 1.143 0.3556) (xy 0.8636 0.3556)
				(xy 0.8636 0.4572) (xy -0.8636 0.4572) (xy -0.8636 0.3556) (xy -1.143 0.3556) (xy -1.143 -0.3556)
				(xy -0.8636 -0.3556) (xy -0.8636 -0.4572)
			)
			(stroke
				(width 0)
				(type default)
			)
			(fill no)
			(layer "F.CrtYd")
		)
		(fp_line
			(start 0.884936 -0.504952)
			(end 0.884936 0.504952)
			(stroke
				(width 0.1)
				(type default)
			)
			(layer "F.Fab")
		)
		(fp_line
			(start -0.884936 -0.504952)
			(end 0.884936 -0.504952)
			(stroke
				(width 0.1)
				(type default)
			)
			(layer "F.Fab")
		)
		(fp_line
			(start 0.884936 0.504952)
			(end -0.884936 0.504952)
			(stroke
				(width 0.1)
				(type default)
			)
			(layer "F.Fab")
		)
		(fp_line
			(start -0.884936 0.504952)
			(end -0.884936 -0.504952)
			(stroke
				(width 0.1)
				(type default)
			)
			(layer "F.Fab")
		)
		(pad "1" smd rect
			(at 0.7366 0 180)
			(size 0.7112 0.8128)
			(layers "F.Cu" "F.Mask" "F.Paste")
			(net "PV_VDDR_NODE1")
		)
		(pad "2" smd rect
			(at -0.7366 0 180)
			(size 0.7112 0.8128)
			(layers "F.Cu" "F.Mask" "F.Paste")
			(net "GND")
		)
	)
	(footprint ""
		(layer "F.Cu")
		(at 171.151042 -139.383008)
		(property "Reference" "R1066"
			(at -2.911094 -9.79932 0)
			(unlocked yes)
			(layer "F.SilkS")
			(effects
				(font
					(size 0.7874 0.5842)
					(thickness 0.1524)
				)
				(justify left)
			)
		)
		(property "Value" ""
			(at 0 0 0)
			(layer "F.Fab")
			(effects
				(font
					(size 1.27 1.27)
				)
			)
		)
		(duplicate_pad_numbers_are_jumpers no)
		(fp_line
			(start -0.7874 -0.4064)
			(end 0.7874 -0.4064)
			(stroke
				(width 0.1524)
				(type default)
			)
			(layer "F.SilkS")
		)
		(fp_line
			(start -0.7874 0.4064)
			(end -0.7874 -0.4064)
			(stroke
				(width 0.1524)
				(type default)
			)
			(layer "F.SilkS")
		)
		(fp_line
			(start 0.7874 -0.4064)
			(end 0.7874 0.4064)
			(stroke
				(width 0.1524)
				(type default)
			)
			(layer "F.SilkS")
		)
		(fp_line
			(start 0.7874 0.4064)
			(end -0.7874 0.4064)
			(stroke
				(width 0.1524)
				(type default)
			)
			(layer "F.SilkS")
		)
		(fp_poly
			(pts
				(xy -0.508 0.2794) (xy -0.508 0.2286) (xy -0.635 0.2286) (xy -0.635 -0.254) (xy -0.5334 -0.254)
				(xy -0.5334 -0.2794) (xy 0.5334 -0.2794) (xy 0.5334 -0.254) (xy 0.635 -0.254) (xy 0.635 0.254) (xy 0.5334 0.254)
				(xy 0.5334 0.2794)
			)
			(stroke
				(width 0)
				(type default)
			)
			(fill no)
			(layer "F.CrtYd")
		)
		(pad "1" smd rect
			(at 0.40005 0)
			(size 0.4572 0.508)
			(layers "F.Cu" "F.Mask" "F.Paste")
			(net "PWR_BTN_NODE1_C_L")
		)
		(pad "2" smd rect
			(at -0.40005 0)
			(size 0.4572 0.508)
			(layers "F.Cu" "F.Mask" "F.Paste")
			(net "FM_CPLD_NODE1_PWR_BTN_L")
		)
	)
	(footprint ""
		(layer "F.Cu")
		(at 108.72724 -142.414498 90)
		(property "Reference" "PR64"
			(at 1.927352 0.092964 90)
			(unlocked yes)
			(layer "F.SilkS")
			(effects
				(font
					(size 0.635 0.4064)
					(thickness 0.1524)
				)
				(justify left)
			)
		)
		(property "Value" ""
			(at 0 0 90)
			(layer "F.Fab")
			(effects
				(font
					(size 1.27 1.27)
				)
			)
		)
		(duplicate_pad_numbers_are_jumpers no)
		(fp_line
			(start 0.7874 -0.4064)
			(end 0.7874 0.4064)
			(stroke
				(width 0.1524)
				(type default)
			)
			(layer "F.SilkS")
		)
		(fp_line
			(start -0.7874 -0.4064)
			(end 0.7874 -0.4064)
			(stroke
				(width 0.1524)
				(type default)
			)
			(layer "F.SilkS")
		)
		(fp_line
			(start 0.7874 0.4064)
			(end -0.7874 0.4064)
			(stroke
				(width 0.1524)
				(type default)
			)
			(layer "F.SilkS")
		)
		(fp_line
			(start -0.7874 0.4064)
			(end -0.7874 -0.4064)
			(stroke
				(width 0.1524)
				(type default)
			)
			(layer "F.SilkS")
		)
		(fp_poly
			(pts
				(xy -0.508 0.2794) (xy -0.508 0.2286) (xy -0.635 0.2286) (xy -0.635 -0.254) (xy -0.5334 -0.254)
				(xy -0.5334 -0.2794) (xy 0.5334 -0.2794) (xy 0.5334 -0.254) (xy 0.635 -0.254) (xy 0.635 0.254) (xy 0.5334 0.254)
				(xy 0.5334 0.2794)
			)
			(stroke
				(width 0)
				(type default)
			)
			(fill no)
			(layer "F.CrtYd")
		)
		(pad "1" smd rect
			(at 0.40005 0 90)
			(size 0.4572 0.508)
			(layers "F.Cu" "F.Mask" "F.Paste")
			(net "VR_PVCCP_NODE1_VCC")
		)
		(pad "2" smd rect
			(at -0.40005 0 90)
			(size 0.4572 0.508)
			(layers "F.Cu" "F.Mask" "F.Paste")
			(net "VR_PVCCP_NODE1_ICCMAX")
		)
	)
	(footprint ""
		(layer "F.Cu")
		(at 159.652208 -74.318114)
		(property "Reference" "C851"
			(at -3.902456 -2.80289 0)
			(unlocked yes)
			(layer "F.SilkS")
			(effects
				(font
					(size 0.7874 0.5842)
					(thickness 0.1524)
				)
				(justify left)
			)
		)
		(property "Value" ""
			(at 0 0 0)
			(layer "F.Fab")
			(effects
				(font
					(size 1.27 1.27)
				)
			)
		)
		(duplicate_pad_numbers_are_jumpers no)
		(fp_line
			(start -0.7874 -0.4064)
			(end 0.7874 -0.4064)
			(stroke
				(width 0.1524)
				(type default)
			)
			(layer "F.SilkS")
		)
		(fp_line
			(start -0.7874 0.4064)
			(end -0.7874 -0.4064)
			(stroke
				(width 0.1524)
				(type default)
			)
			(layer "F.SilkS")
		)
		(fp_line
			(start 0 0.381)
			(end 0 -0.381)
			(stroke
				(width 0.1524)
				(type default)
			)
			(layer "F.SilkS")
		)
		(fp_line
			(start 0.7874 -0.4064)
			(end 0.7874 0.4064)
			(stroke
				(width 0.1524)
				(type default)
			)
			(layer "F.SilkS")
		)
		(fp_line
			(start 0.7874 0.4064)
			(end -0.7874 0.4064)
			(stroke
				(width 0.1524)
				(type default)
			)
			(layer "F.SilkS")
		)
		(fp_poly
			(pts
				(xy -0.5334 0.254) (xy -0.635 0.254) (xy -0.635 0.2286) (xy -0.635 -0.254) (xy -0.5334 -0.254) (xy -0.5334 -0.2794)
				(xy 0.5334 -0.2794) (xy 0.5334 -0.254) (xy 0.635 -0.254) (xy 0.635 0.254) (xy 0.5334 0.254) (xy 0.5334 0.2794)
				(xy -0.508 0.2794) (xy -0.5334 0.2794)
			)
			(stroke
				(width 0)
				(type default)
			)
			(fill no)
			(layer "F.CrtYd")
		)
		(pad "1" smd rect
			(at 0.40005 0)
			(size 0.4572 0.508)
			(layers "F.Cu" "F.Mask" "F.Paste")
			(net "P1V0_ADJ")
		)
		(pad "2" smd rect
			(at -0.40005 0)
			(size 0.4572 0.508)
			(layers "F.Cu" "F.Mask" "F.Paste")
			(net "P1V0_ADJ_S")
		)
	)
	(footprint ""
		(layer "F.Cu")
		(at 111.74476 -188.126624 90)
		(property "Reference" "C647"
			(at 5.151882 1.617472 90)
			(unlocked yes)
			(layer "F.SilkS")
			(effects
				(font
					(size 0.7874 0.5842)
					(thickness 0.1524)
				)
				(justify left)
			)
		)
		(property "Value" ""
			(at 0 0 90)
			(layer "F.Fab")
			(effects
				(font
					(size 1.27 1.27)
				)
			)
		)
		(duplicate_pad_numbers_are_jumpers no)
		(fp_line
			(start 0.7874 -0.4064)
			(end 0.7874 0.4064)
			(stroke
				(width 0.1524)
				(type default)
			)
			(layer "F.SilkS")
		)
		(fp_line
			(start -0.7874 -0.4064)
			(end 0.7874 -0.4064)
			(stroke
				(width 0.1524)
				(type default)
			)
			(layer "F.SilkS")
		)
		(fp_line
			(start 0 0.381)
			(end 0 -0.381)
			(stroke
				(width 0.1524)
				(type default)
			)
			(layer "F.SilkS")
		)
		(fp_line
			(start 0.7874 0.4064)
			(end -0.7874 0.4064)
			(stroke
				(width 0.1524)
				(type default)
			)
			(layer "F.SilkS")
		)
		(fp_line
			(start -0.7874 0.4064)
			(end -0.7874 -0.4064)
			(stroke
				(width 0.1524)
				(type default)
			)
			(layer "F.SilkS")
		)
		(fp_poly
			(pts
				(xy -0.5334 0.254) (xy -0.635 0.254) (xy -0.635 0.2286) (xy -0.635 -0.254) (xy -0.5334 -0.254) (xy -0.5334 -0.2794)
				(xy 0.5334 -0.2794) (xy 0.5334 -0.254) (xy 0.635 -0.254) (xy 0.635 0.254) (xy 0.5334 0.254) (xy 0.5334 0.2794)
				(xy -0.508 0.2794) (xy -0.5334 0.2794)
			)
			(stroke
				(width 0)
				(type default)
			)
			(fill no)
			(layer "F.CrtYd")
		)
		(pad "1" smd rect
			(at 0.40005 0 90)
			(size 0.4572 0.508)
			(layers "F.Cu" "F.Mask" "F.Paste")
			(net "T6_NODE1_EN_R")
		)
		(pad "2" smd rect
			(at -0.40005 0 90)
			(size 0.4572 0.508)
			(layers "F.Cu" "F.Mask" "F.Paste")
			(net "GND")
		)
	)
	(footprint ""
		(layer "F.Cu")
		(at 123.301252 -137.03935 180)
		(property "Reference" "R281"
			(at 0.967232 -1.41986 0)
			(unlocked yes)
			(layer "F.SilkS")
			(effects
				(font
					(size 0.7874 0.5842)
					(thickness 0.1524)
				)
				(justify left)
			)
		)
		(property "Value" ""
			(at 0 0 180)
			(layer "F.Fab")
			(effects
				(font
					(size 1.27 1.27)
				)
			)
		)
		(duplicate_pad_numbers_are_jumpers no)
		(fp_line
			(start 0.7874 0.4064)
			(end -0.7874 0.4064)
			(stroke
				(width 0.1524)
				(type default)
			)
			(layer "F.SilkS")
		)
		(fp_line
			(start 0.7874 -0.4064)
			(end 0.7874 0.4064)
			(stroke
				(width 0.1524)
				(type default)
			)
			(layer "F.SilkS")
		)
		(fp_line
			(start -0.7874 0.4064)
			(end -0.7874 -0.4064)
			(stroke
				(width 0.1524)
				(type default)
			)
			(layer "F.SilkS")
		)
		(fp_line
			(start -0.7874 -0.4064)
			(end 0.7874 -0.4064)
			(stroke
				(width 0.1524)
				(type default)
			)
			(layer "F.SilkS")
		)
		(fp_poly
			(pts
				(xy -0.508 0.2794) (xy -0.508 0.2286) (xy -0.635 0.2286) (xy -0.635 -0.254) (xy -0.5334 -0.254)
				(xy -0.5334 -0.2794) (xy 0.5334 -0.2794) (xy 0.5334 -0.254) (xy 0.635 -0.254) (xy 0.635 0.254) (xy 0.5334 0.254)
				(xy 0.5334 0.2794)
			)
			(stroke
				(width 0)
				(type default)
			)
			(fill no)
			(layer "F.CrtYd")
		)
		(pad "1" smd rect
			(at 0.40005 0 180)
			(size 0.4572 0.508)
			(layers "F.Cu" "F.Mask" "F.Paste")
			(net "P3V3_NODE1")
		)
		(pad "2" smd rect
			(at -0.40005 0 180)
			(size 0.4572 0.508)
			(layers "F.Cu" "F.Mask" "F.Paste")
			(net "PE_SW_BMC_PERST_L")
		)
	)
	(footprint ""
		(layer "F.Cu")
		(at 159.351726 -76.74102 90)
		(property "Reference" "PC29"
			(at 2.55778 -3.601974 0)
			(unlocked yes)
			(layer "F.SilkS")
			(effects
				(font
					(size 0.7874 0.5842)
					(thickness 0.1524)
				)
				(justify left)
			)
		)
		(property "Value" ""
			(at 0 0 90)
			(layer "F.Fab")
			(effects
				(font
					(size 1.27 1.27)
				)
			)
		)
		(duplicate_pad_numbers_are_jumpers no)
		(fp_line
			(start 0.7874 -0.4064)
			(end 0.7874 0.4064)
			(stroke
				(width 0.1524)
				(type default)
			)
			(layer "F.SilkS")
		)
		(fp_line
			(start -0.7874 -0.4064)
			(end 0.7874 -0.4064)
			(stroke
				(width 0.1524)
				(type default)
			)
			(layer "F.SilkS")
		)
		(fp_line
			(start 0 0.381)
			(end 0 -0.381)
			(stroke
				(width 0.1524)
				(type default)
			)
			(layer "F.SilkS")
		)
		(fp_line
			(start 0.7874 0.4064)
			(end -0.7874 0.4064)
			(stroke
				(width 0.1524)
				(type default)
			)
			(layer "F.SilkS")
		)
		(fp_line
			(start -0.7874 0.4064)
			(end -0.7874 -0.4064)
			(stroke
				(width 0.1524)
				(type default)
			)
			(layer "F.SilkS")
		)
		(fp_poly
			(pts
				(xy -0.5334 0.254) (xy -0.635 0.254) (xy -0.635 0.2286) (xy -0.635 -0.254) (xy -0.5334 -0.254) (xy -0.5334 -0.2794)
				(xy 0.5334 -0.2794) (xy 0.5334 -0.254) (xy 0.635 -0.254) (xy 0.635 0.254) (xy 0.5334 0.254) (xy 0.5334 0.2794)
				(xy -0.508 0.2794) (xy -0.5334 0.2794)
			)
			(stroke
				(width 0)
				(type default)
			)
			(fill no)
			(layer "F.CrtYd")
		)
		(pad "1" smd rect
			(at 0.40005 0 90)
			(size 0.4572 0.508)
			(layers "F.Cu" "F.Mask" "F.Paste")
			(net "P1V0_NODE1")
		)
		(pad "2" smd rect
			(at -0.40005 0 90)
			(size 0.4572 0.508)
			(layers "F.Cu" "F.Mask" "F.Paste")
			(net "GND")
		)
	)
)
